# T6G (Grand Teton) — schematic netlist excerpt (pin names and nets, part order shuffled) for the footprints in the layout excerpt that follows; sources: Cadence DE-HDL packaged netlist, KiCad conversion of 04192023_DAF0TMB3IC0_F0TG_MB_C_brd_V02_OCP.brd

PR2526  Q_RES  10 1% CHIP  pkg 0402LF  page 266 : A = P12V_HSC_SENSE2_N ; B = P12V_HSC_SENSE2_R3_N
C1001  Q_CAP  0.1UF 10V 10% X7S  pkg C0201  page 312 : A = P1V8_CPU0_RT3_1A ; B = GND
R4143  Q_RES  33.2 1% CHIP  pkg 0402LF  page 81 : A = GPU_3V3IO_RSVD0_FFU_ISO_R ; B = GPU_3V3IO_RSVD0_FFU_ISO

(kicad_pcb
	(version 20260206)
	(generator "pcbnew")
	(generator_version "10.0")
	(general
		(thickness 1.6)
		(legacy_teardrops no)
	)
	(paper "A4")
	(title_block
		(title "04192023_DAF0TMB3IC0_F0TG_MB_C_brd_V02_OCP.brd")
		(comment 1 "Grand Teton / footprints 6773-6775 of 8354")
	)
	(layers
		(0 "F.Cu" signal "TOP")
		(4 "In1.Cu" signal "GND")
		(6 "In2.Cu" signal "IN1")
		(8 "In3.Cu" signal "GND1")
		(10 "In4.Cu" signal "IN2")
		(12 "In5.Cu" signal "GND2")
		(14 "In6.Cu" signal "IN3")
		(16 "In7.Cu" signal "GND3")
		(18 "In8.Cu" signal "VCC")
		(20 "In9.Cu" signal "VCC1")
		(22 "In10.Cu" signal "GND4")
		(24 "In11.Cu" signal "IN4")
		(26 "In12.Cu" signal "GND5")
		(28 "In13.Cu" signal "IN5")
		(30 "In14.Cu" signal "GND6")
		(32 "In15.Cu" signal "IN6")
		(34 "In16.Cu" signal "GND7")
		(2 "B.Cu" signal "BOTTOM")
		(9 "F.Adhes" user "F.Adhesive")
		(11 "B.Adhes" user "B.Adhesive")
		(13 "F.Paste" user "Package Geometry/Pastemask Top")
		(15 "B.Paste" user "Package Geometry/Pastemask Bottom")
		(5 "F.SilkS" user "Ref Des/Silkscreen Top")
		(7 "B.SilkS" user "Ref Des/Silkscreen Bottom")
		(1 "F.Mask" user "Board Geometry/Soldermask Top")
		(3 "B.Mask" user "Board Geometry/Soldermask Bottom")
		(17 "Dwgs.User" user "User.Drawings")
		(19 "Cmts.User" user "User.Comments")
		(21 "Eco1.User" user "User.Eco1")
		(23 "Eco2.User" user "User.Eco2")
		(25 "Edge.Cuts" user "Board Geometry/Outline")
		(27 "Margin" user)
		(31 "F.CrtYd" user "Package Geometry/Place Bound Top")
		(29 "B.CrtYd" user "Package Geometry/Place Bound Bottom")
		(35 "F.Fab" user "Ref Des/Assembly Top")
		(33 "B.Fab" user "Ref Des/Assembly Bottom")
	)
	(footprint ""
		(layer "B.Cu")
		(at 377.678442 -395.148562 90)
		(property "Reference" "C1001"
			(at 0 0 90)
			(layer "B.SilkS")
			(hide yes)
			(effects
				(font
					(size 1.27 1.27)
				)
				(justify mirror)
			)
		)
		(property "Value" ""
			(at 0 0 90)
			(layer "B.Fab")
			(effects
				(font
					(size 1.27 1.27)
				)
				(justify mirror)
			)
		)
		(duplicate_pad_numbers_are_jumpers no)
		(fp_line
			(start 0.299974 -0.150114)
			(end -0.299974 -0.150114)
			(stroke
				(width 0.1)
				(type default)
			)
			(layer "B.Fab")
		)
		(fp_line
			(start -0.299974 -0.150114)
			(end -0.299974 0.150114)
			(stroke
				(width 0.1)
				(type default)
			)
			(layer "B.Fab")
		)
		(fp_line
			(start 0.299974 0.150114)
			(end 0.299974 -0.150114)
			(stroke
				(width 0.1)
				(type default)
			)
			(layer "B.Fab")
		)
		(fp_line
			(start -0.299974 0.150114)
			(end 0.299974 0.150114)
			(stroke
				(width 0.1)
				(type default)
			)
			(layer "B.Fab")
		)
		(pad "1" smd rect
			(at 0.2667 0 270)
			(size 0.3048 0.381)
			(layers "B.Cu" "B.Mask" "B.Paste")
			(net "P1V8_CPU0_RT3_1A")
		)
		(pad "2" smd rect
			(at -0.2667 0 270)
			(size 0.3048 0.381)
			(layers "B.Cu" "B.Mask" "B.Paste")
			(net "GND")
		)
	)
	(footprint ""
		(layer "B.Cu")
		(at 197.269608 -120.737376 180)
		(property "Reference" "R4143"
			(at 0 0 0)
			(layer "B.SilkS")
			(hide yes)
			(effects
				(font
					(size 1.27 1.27)
				)
				(justify mirror)
			)
		)
		(property "Value" ""
			(at 0 0 0)
			(layer "B.Fab")
			(effects
				(font
					(size 1.27 1.27)
				)
				(justify mirror)
			)
		)
		(duplicate_pad_numbers_are_jumpers no)
		(fp_line
			(start 0.7874 0.4064)
			(end 0.7874 -0.4064)
			(stroke
				(width 0.1524)
				(type default)
			)
			(layer "B.SilkS")
		)
		(fp_line
			(start 0.7874 -0.4064)
			(end -0.7874 -0.4064)
			(stroke
				(width 0.1524)
				(type default)
			)
			(layer "B.SilkS")
		)
		(fp_line
			(start -0.7874 0.4064)
			(end 0.7874 0.4064)
			(stroke
				(width 0.1524)
				(type default)
			)
			(layer "B.SilkS")
		)
		(fp_line
			(start -0.7874 -0.4064)
			(end -0.7874 0.4064)
			(stroke
				(width 0.1524)
				(type default)
			)
			(layer "B.SilkS")
		)
		(fp_line
			(start 0.67945 0.3048)
			(end 0.67945 -0.305054)
			(stroke
				(width 0.1)
				(type default)
			)
			(layer "B.Fab")
		)
		(fp_line
			(start 0.67945 -0.305054)
			(end 0.12065 -0.305054)
			(stroke
				(width 0.1)
				(type default)
			)
			(layer "B.Fab")
		)
		(fp_line
			(start 0.12065 0.3048)
			(end 0.67945 0.3048)
			(stroke
				(width 0.1)
				(type default)
			)
			(layer "B.Fab")
		)
		(fp_line
			(start 0.12065 0.2794)
			(end 0.12065 0.3048)
			(stroke
				(width 0.1)
				(type default)
			)
			(layer "B.Fab")
		)
		(fp_line
			(start 0.12065 -0.2794)
			(end -0.12065 -0.2794)
			(stroke
				(width 0.1)
				(type default)
			)
			(layer "B.Fab")
		)
		(fp_line
			(start 0.12065 -0.305054)
			(end 0.12065 -0.2794)
			(stroke
				(width 0.1)
				(type default)
			)
			(layer "B.Fab")
		)
		(fp_line
			(start -0.120396 0.3048)
			(end -0.120396 0.2794)
			(stroke
				(width 0.1)
				(type default)
			)
			(layer "B.Fab")
		)
		(fp_line
			(start -0.120396 0.2794)
			(end 0.12065 0.2794)
			(stroke
				(width 0.1)
				(type default)
			)
			(layer "B.Fab")
		)
		(fp_line
			(start -0.12065 -0.2794)
			(end -0.12065 -0.3048)
			(stroke
				(width 0.1)
				(type default)
			)
			(layer "B.Fab")
		)
		(fp_line
			(start -0.12065 -0.3048)
			(end -0.67945 -0.3048)
			(stroke
				(width 0.1)
				(type default)
			)
			(layer "B.Fab")
		)
		(fp_line
			(start -0.67945 0.3048)
			(end -0.120396 0.3048)
			(stroke
				(width 0.1)
				(type default)
			)
			(layer "B.Fab")
		)
		(fp_line
			(start -0.67945 -0.3048)
			(end -0.67945 0.3048)
			(stroke
				(width 0.1)
				(type default)
			)
			(layer "B.Fab")
		)
		(pad "1" smd circle
			(at 0.40005 0)
			(size 0 0)
			(layers "B.Cu" "B.Mask" "B.Paste")
			(net "GPU_3V3IO_RSVD0_FFU_ISO_R")
		)
		(pad "2" smd circle
			(at -0.40005 0)
			(size 0 0)
			(layers "B.Cu" "B.Mask" "B.Paste")
			(net "GPU_3V3IO_RSVD0_FFU_ISO")
		)
	)
	(footprint ""
		(layer "B.Cu")
		(at 206.429356 -381.222504 180)
		(property "Reference" "PR2526"
			(at 0 0 0)
			(layer "B.SilkS")
			(hide yes)
			(effects
				(font
					(size 1.27 1.27)
				)
				(justify mirror)
			)
		)
		(property "Value" ""
			(at 0 0 0)
			(layer "B.Fab")
			(effects
				(font
					(size 1.27 1.27)
				)
				(justify mirror)
			)
		)
		(duplicate_pad_numbers_are_jumpers no)
		(fp_line
			(start 0.7874 0.4064)
			(end 0.7874 -0.4064)
			(stroke
				(width 0.1524)
				(type default)
			)
			(layer "B.SilkS")
		)
		(fp_line
			(start 0.7874 -0.4064)
			(end -0.7874 -0.4064)
			(stroke
				(width 0.1524)
				(type default)
			)
			(layer "B.SilkS")
		)
		(fp_line
			(start -0.7874 0.4064)
			(end 0.7874 0.4064)
			(stroke
				(width 0.1524)
				(type default)
			)
			(layer "B.SilkS")
		)
		(fp_line
			(start -0.7874 -0.4064)
			(end -0.7874 0.4064)
			(stroke
				(width 0.1524)
				(type default)
			)
			(layer "B.SilkS")
		)
		(fp_line
			(start 0.67945 0.3048)
			(end 0.67945 -0.305054)
			(stroke
				(width 0.1)
				(type default)
			)
			(layer "B.Fab")
		)
		(fp_line
			(start 0.67945 -0.305054)
			(end 0.12065 -0.305054)
			(stroke
				(width 0.1)
				(type default)
			)
			(layer "B.Fab")
		)
		(fp_line
			(start 0.12065 0.3048)
			(end 0.67945 0.3048)
			(stroke
				(width 0.1)
				(type default)
			)
			(layer "B.Fab")
		)
		(fp_line
			(start 0.12065 0.2794)
			(end 0.12065 0.3048)
			(stroke
				(width 0.1)
				(type default)
			)
			(layer "B.Fab")
		)
		(fp_line
			(start 0.12065 -0.2794)
			(end -0.12065 -0.2794)
			(stroke
				(width 0.1)
				(type default)
			)
			(layer "B.Fab")
		)
		(fp_line
			(start 0.12065 -0.305054)
			(end 0.12065 -0.2794)
			(stroke
				(width 0.1)
				(type default)
			)
			(layer "B.Fab")
		)
		(fp_line
			(start -0.120396 0.3048)
			(end -0.120396 0.2794)
			(stroke
				(width 0.1)
				(type default)
			)
			(layer "B.Fab")
		)
		(fp_line
			(start -0.120396 0.2794)
			(end 0.12065 0.2794)
			(stroke
				(width 0.1)
				(type default)
			)
			(layer "B.Fab")
		)
		(fp_line
			(start -0.12065 -0.2794)
			(end -0.12065 -0.3048)
			(stroke
				(width 0.1)
				(type default)
			)
			(layer "B.Fab")
		)
		(fp_line
			(start -0.12065 -0.3048)
			(end -0.67945 -0.3048)
			(stroke
				(width 0.1)
				(type default)
			)
			(layer "B.Fab")
		)
		(fp_line
			(start -0.67945 0.3048)
			(end -0.120396 0.3048)
			(stroke
				(width 0.1)
				(type default)
			)
			(layer "B.Fab")
		)
		(fp_line
			(start -0.67945 -0.3048)
			(end -0.67945 0.3048)
			(stroke
				(width 0.1)
				(type default)
			)
			(layer "B.Fab")
		)
		(pad "1" smd circle
			(at 0.40005 0)
			(size 0 0)
			(layers "B.Cu" "B.Mask" "B.Paste")
			(net "P12V_HSC_SENSE2_N")
		)
		(pad "2" smd circle
			(at -0.40005 0)
			(size 0 0)
			(layers "B.Cu" "B.Mask" "B.Paste")
			(net "P12V_HSC_SENSE2_R3_N")
		)
	)
)
